(kicad_pcb
	(version 20260206)
	(generator "pcbnew")
	(generator_version "10.0")
	(general
		(thickness 1.6)
		(legacy_teardrops no)
	)
	(paper "A4")
	(title_block
		(title "panther-plus-userver — 13130-1b_20150205.brd")
		(comment 1 "Honey Badger (Wiwynn) / footprint 406 of 1509 (DIMM2), pads 142-148 of 210")
	)
	(layers
		(0 "F.Cu" signal "TOP")
		(4 "In1.Cu" signal "L2")
		(6 "In2.Cu" signal "L3")
		(8 "In3.Cu" signal "L4")
		(10 "In4.Cu" signal "L5")
		(12 "In5.Cu" signal "L6")
		(14 "In6.Cu" signal "L7")
		(16 "In7.Cu" signal "L8")
		(18 "In8.Cu" signal "L9")
		(20 "In9.Cu" signal "L10")
		(22 "In10.Cu" signal "L11")
		(2 "B.Cu" signal "BOTTOM")
		(9 "F.Adhes" user "F.Adhesive")
		(11 "B.Adhes" user "B.Adhesive")
		(13 "F.Paste" user "Package Geometry/Pastemask Top")
		(15 "B.Paste" user "Package Geometry/Pastemask Bottom")
		(5 "F.SilkS" user "Ref Des/Silkscreen Top")
		(7 "B.SilkS" user "Ref Des/Silkscreen Bottom")
		(1 "F.Mask" user "Board Geometry/Soldermask Top")
		(3 "B.Mask" user "Board Geometry/Soldermask Bottom")
		(17 "Dwgs.User" user "User.Drawings")
		(19 "Cmts.User" user "User.Comments")
		(21 "Eco1.User" user "User.Eco1")
		(23 "Eco2.User" user "User.Eco2")
		(25 "Edge.Cuts" user "Board Geometry/Outline")
		(27 "Margin" user)
		(31 "F.CrtYd" user "Package Geometry/Place Bound Top")
		(29 "B.CrtYd" user "Package Geometry/Place Bound Bottom")
		(35 "F.Fab" user "Ref Des/Assembly Top")
		(33 "B.Fab" user "Ref Des/Assembly Bottom")
	)
	(footprint ""
		(layer "F.Cu")
		(at 158.500064 -66.699892 180)
		(property "Reference" "DIMM2"
			(at 0 0 180)
			(layer "F.SilkS")
			(hide yes)
			(effects
				(font
					(size 1.27 1.27)
				)
			)
		)
		(property "Value" "DDR3-204P-174-COLAY-1-GP"
			(at -40.682164 -17.468088 180)
			(unlocked yes)
			(layer "F.Fab")
			(hide yes)
			(effects
				(font
					(size 1.016 1.016)
					(thickness 0.1524)
				)
			)
		)
		(property "Device Type" "AS0A626-H8SN-7H-COLAY-1"
			(at -40.682164 -18.992088 180)
			(unlocked yes)
			(layer "F.Fab")
			(hide yes)
			(effects
				(font
					(size 1.016 1.016)
					(thickness 0.1524)
				)
			)
		)
		(duplicate_pad_numbers_are_jumpers no)
		(pad "140" smd custom
			(at 12.450064 -4.106672 180)
			(size 0.1143 0.1143)
			(layers "F.Cu" "F.Mask" "F.Paste")
			(net "GND")
			(options
				(clearance outline)
				(anchor circle)
			)
			(primitives
				(gr_poly
					(pts
						(xy 0 0.9017) (xy -0.03175 0.89916) (xy -0.0635 0.889) (xy -0.09144 0.87376) (xy -0.11684 0.85344)
						(xy -0.13716 0.82804) (xy -0.1524 0.8001) (xy -0.16256 0.76835) (xy -0.1651 0.7366) (xy -0.1651 0.19685)
						(xy -0.17272 0.18923) (xy -0.17907 0.18034) (xy -0.18669 0.17145) (xy -0.19177 0.16256) (xy -0.19812 0.15367)
						(xy -0.20828 0.13335) (xy -0.21971 0.10287) (xy -0.22225 0.09271) (xy -0.22479 0.08128) (xy -0.22606 0.07112)
						(xy -0.2286 0.05969) (xy -0.2286 0.01651) (xy -0.22606 0.00508) (xy -0.22479 -0.00508) (xy -0.22225 -0.01651)
						(xy -0.21971 -0.02667) (xy -0.20828 -0.05715) (xy -0.19812 -0.07747) (xy -0.19177 -0.08636) (xy -0.18669 -0.09525)
						(xy -0.17907 -0.10414) (xy -0.17272 -0.11303) (xy -0.1651 -0.12065) (xy -0.1651 -0.7366) (xy -0.16256 -0.76835)
						(xy -0.1524 -0.8001) (xy -0.13716 -0.82804) (xy -0.11684 -0.85344) (xy -0.09144 -0.87376) (xy -0.0635 -0.889)
						(xy -0.03175 -0.89916) (xy 0 -0.9017) (xy 0.03175 -0.89916) (xy 0.0635 -0.889) (xy 0.09144 -0.87376)
						(xy 0.11684 -0.85344) (xy 0.13716 -0.82804) (xy 0.1524 -0.8001) (xy 0.16256 -0.76835) (xy 0.1651 -0.7366)
						(xy 0.1651 -0.11938) (xy 0.17272 -0.11176) (xy 0.19812 -0.0762) (xy 0.2032 -0.06604) (xy 0.20701 -0.05715)
						(xy 0.21209 -0.04699) (xy 0.2159 -0.03683) (xy 0.21844 -0.02667) (xy 0.22225 -0.01524) (xy 0.22352 -0.00508)
						(xy 0.22606 0.00508) (xy 0.22733 0.01651) (xy 0.22733 0.02667) (xy 0.2286 0.0381) (xy 0.22733 0.04953)
						(xy 0.22733 0.05969) (xy 0.22606 0.07112) (xy 0.22352 0.08128) (xy 0.22225 0.09144) (xy 0.21844 0.10287)
						(xy 0.2159 0.11303) (xy 0.21209 0.12319) (xy 0.20701 0.13335) (xy 0.2032 0.14224) (xy 0.19812 0.1524)
						(xy 0.17272 0.18796) (xy 0.1651 0.19558) (xy 0.1651 0.7366) (xy 0.16256 0.76835) (xy 0.1524 0.8001)
						(xy 0.13716 0.82804) (xy 0.11684 0.85344) (xy 0.09144 0.87376) (xy 0.0635 0.889) (xy 0.03175 0.89916)
					)
					(width 0)
					(fill yes)
				)
			)
		)
		(pad "141" smd custom
			(at 12.750038 4.106672 180)
			(size 0.1143 0.1143)
			(layers "F.Cu" "F.Mask" "F.Paste")
			(net "M_A_DQS_DP4")
			(options
				(clearance outline)
				(anchor circle)
			)
			(primitives
				(gr_poly
					(pts
						(xy 0 0.9017) (xy -0.03175 0.89916) (xy -0.0635 0.889) (xy -0.09144 0.87376) (xy -0.11684 0.85344)
						(xy -0.13716 0.82804) (xy -0.1524 0.8001) (xy -0.16256 0.76835) (xy -0.1651 0.7366) (xy -0.1651 -0.13462)
						(xy -0.17272 -0.14224) (xy -0.19812 -0.1778) (xy -0.2032 -0.18796) (xy -0.20701 -0.19685) (xy -0.21209 -0.20701)
						(xy -0.2159 -0.21717) (xy -0.21844 -0.22733) (xy -0.22225 -0.23876) (xy -0.22352 -0.24892) (xy -0.22606 -0.25908)
						(xy -0.22733 -0.27051) (xy -0.22733 -0.28067) (xy -0.2286 -0.2921) (xy -0.22733 -0.30353) (xy -0.22733 -0.31369)
						(xy -0.22606 -0.32512) (xy -0.22352 -0.33528) (xy -0.22225 -0.34544) (xy -0.21844 -0.35687) (xy -0.2159 -0.36703)
						(xy -0.21209 -0.37719) (xy -0.20701 -0.38735) (xy -0.2032 -0.39624) (xy -0.19812 -0.4064) (xy -0.17272 -0.44196)
						(xy -0.1651 -0.44958) (xy -0.1651 -0.7366) (xy -0.16256 -0.76835) (xy -0.1524 -0.8001) (xy -0.13716 -0.82804)
						(xy -0.11684 -0.85344) (xy -0.09144 -0.87376) (xy -0.0635 -0.889) (xy -0.03175 -0.89916) (xy 0 -0.9017)
						(xy 0.03175 -0.89916) (xy 0.0635 -0.889) (xy 0.09144 -0.87376) (xy 0.11684 -0.85344) (xy 0.13716 -0.82804)
						(xy 0.1524 -0.8001) (xy 0.16256 -0.76835) (xy 0.1651 -0.7366) (xy 0.1651 -0.44958) (xy 0.17272 -0.44196)
						(xy 0.19812 -0.4064) (xy 0.2032 -0.39624) (xy 0.20701 -0.38735) (xy 0.21209 -0.37719) (xy 0.2159 -0.36703)
						(xy 0.21844 -0.35687) (xy 0.22225 -0.34544) (xy 0.22352 -0.33528) (xy 0.22606 -0.32512) (xy 0.22733 -0.31369)
						(xy 0.22733 -0.30353) (xy 0.2286 -0.2921) (xy 0.22733 -0.28067) (xy 0.22733 -0.27051) (xy 0.22606 -0.25908)
						(xy 0.22352 -0.24892) (xy 0.22225 -0.23876) (xy 0.21844 -0.22733) (xy 0.2159 -0.21717) (xy 0.21209 -0.20701)
						(xy 0.20701 -0.19685) (xy 0.2032 -0.18796) (xy 0.19812 -0.1778) (xy 0.17272 -0.14224) (xy 0.1651 -0.13462)
						(xy 0.1651 0.7366) (xy 0.16256 0.76835) (xy 0.1524 0.8001) (xy 0.13716 0.82804) (xy 0.11684 0.85344)
						(xy 0.09144 0.87376) (xy 0.0635 0.889) (xy 0.03175 0.89916)
					)
					(width 0)
					(fill yes)
				)
			)
		)
		(pad "142" smd custom
			(at 13.050012 -4.106672 180)
			(size 0.1143 0.1143)
			(layers "F.Cu" "F.Mask" "F.Paste")
			(net "M_A_DQ34")
			(options
				(clearance outline)
				(anchor circle)
			)
			(primitives
				(gr_poly
					(pts
						(xy 0 0.9017) (xy -0.03175 0.89916) (xy -0.0635 0.889) (xy -0.09144 0.87376) (xy -0.11684 0.85344)
						(xy -0.13716 0.82804) (xy -0.1524 0.8001) (xy -0.16256 0.76835) (xy -0.1651 0.7366) (xy -0.1651 0.44958)
						(xy -0.17272 0.44196) (xy -0.19812 0.4064) (xy -0.2032 0.39624) (xy -0.20701 0.38735) (xy -0.21209 0.37719)
						(xy -0.2159 0.36703) (xy -0.21844 0.35687) (xy -0.22225 0.34544) (xy -0.22352 0.33528) (xy -0.22606 0.32512)
						(xy -0.22733 0.31369) (xy -0.22733 0.30353) (xy -0.2286 0.2921) (xy -0.22733 0.28067) (xy -0.22733 0.27051)
						(xy -0.22606 0.25908) (xy -0.22352 0.24892) (xy -0.22225 0.23876) (xy -0.21844 0.22733) (xy -0.2159 0.21717)
						(xy -0.21209 0.20701) (xy -0.20701 0.19685) (xy -0.2032 0.18796) (xy -0.19812 0.1778) (xy -0.17272 0.14224)
						(xy -0.1651 0.13462) (xy -0.1651 -0.7366) (xy -0.16256 -0.76835) (xy -0.1524 -0.8001) (xy -0.13716 -0.82804)
						(xy -0.11684 -0.85344) (xy -0.09144 -0.87376) (xy -0.0635 -0.889) (xy -0.03175 -0.89916) (xy 0 -0.9017)
						(xy 0.03175 -0.89916) (xy 0.0635 -0.889) (xy 0.09144 -0.87376) (xy 0.11684 -0.85344) (xy 0.13716 -0.82804)
						(xy 0.1524 -0.8001) (xy 0.16256 -0.76835) (xy 0.1651 -0.7366) (xy 0.1651 0.13462) (xy 0.17272 0.14224)
						(xy 0.19812 0.1778) (xy 0.2032 0.18796) (xy 0.20701 0.19685) (xy 0.21209 0.20701) (xy 0.2159 0.21717)
						(xy 0.21844 0.22733) (xy 0.22225 0.23876) (xy 0.22352 0.24892) (xy 0.22606 0.25908) (xy 0.22733 0.27051)
						(xy 0.22733 0.28067) (xy 0.2286 0.2921) (xy 0.22733 0.30353) (xy 0.22733 0.31369) (xy 0.22606 0.32512)
						(xy 0.22352 0.33528) (xy 0.22225 0.34544) (xy 0.21844 0.35687) (xy 0.2159 0.36703) (xy 0.21209 0.37719)
						(xy 0.20701 0.38735) (xy 0.2032 0.39624) (xy 0.19812 0.4064) (xy 0.17272 0.44196) (xy 0.1651 0.44958)
						(xy 0.1651 0.7366) (xy 0.16256 0.76835) (xy 0.1524 0.8001) (xy 0.13716 0.82804) (xy 0.11684 0.85344)
						(xy 0.09144 0.87376) (xy 0.0635 0.889) (xy 0.03175 0.89916)
					)
					(width 0)
					(fill yes)
				)
			)
		)
		(pad "143" smd custom
			(at 13.349986 4.106672 180)
			(size 0.1143 0.1143)
			(layers "F.Cu" "F.Mask" "F.Paste")
			(net "GND")
			(options
				(clearance outline)
				(anchor circle)
			)
			(primitives
				(gr_poly
					(pts
						(xy 0 0.9017) (xy -0.03175 0.89916) (xy -0.0635 0.889) (xy -0.09144 0.87376) (xy -0.11684 0.85344)
						(xy -0.13716 0.82804) (xy -0.1524 0.8001) (xy -0.16256 0.76835) (xy -0.1651 0.7366) (xy -0.1651 0.11938)
						(xy -0.17272 0.11176) (xy -0.19812 0.0762) (xy -0.2032 0.06604) (xy -0.20701 0.05715) (xy -0.21209 0.04699)
						(xy -0.2159 0.03683) (xy -0.21844 0.02667) (xy -0.22225 0.01524) (xy -0.22352 0.00508) (xy -0.22606 -0.00508)
						(xy -0.22733 -0.01651) (xy -0.22733 -0.02667) (xy -0.2286 -0.0381) (xy -0.22733 -0.04953) (xy -0.22733 -0.05969)
						(xy -0.22606 -0.07112) (xy -0.22352 -0.08128) (xy -0.22225 -0.09144) (xy -0.21844 -0.10287) (xy -0.2159 -0.11303)
						(xy -0.21209 -0.12319) (xy -0.20701 -0.13335) (xy -0.2032 -0.14224) (xy -0.19812 -0.1524) (xy -0.17272 -0.18796)
						(xy -0.1651 -0.19558) (xy -0.1651 -0.7366) (xy -0.16256 -0.76835) (xy -0.1524 -0.8001) (xy -0.13716 -0.82804)
						(xy -0.11684 -0.85344) (xy -0.09144 -0.87376) (xy -0.0635 -0.889) (xy -0.03175 -0.89916) (xy 0 -0.9017)
						(xy 0.03175 -0.89916) (xy 0.0635 -0.889) (xy 0.09144 -0.87376) (xy 0.11684 -0.85344) (xy 0.13716 -0.82804)
						(xy 0.1524 -0.8001) (xy 0.16256 -0.76835) (xy 0.1651 -0.7366) (xy 0.1651 -0.19685) (xy 0.17272 -0.18923)
						(xy 0.17907 -0.18034) (xy 0.18669 -0.17145) (xy 0.19177 -0.16256) (xy 0.19812 -0.15367) (xy 0.20828 -0.13335)
						(xy 0.21971 -0.10287) (xy 0.22225 -0.09271) (xy 0.22479 -0.08128) (xy 0.22606 -0.07112) (xy 0.2286 -0.05969)
						(xy 0.2286 -0.01651) (xy 0.22606 -0.00508) (xy 0.22479 0.00508) (xy 0.22225 0.01651) (xy 0.21971 0.02667)
						(xy 0.20828 0.05715) (xy 0.19812 0.07747) (xy 0.19177 0.08636) (xy 0.18669 0.09525) (xy 0.17907 0.10414)
						(xy 0.17272 0.11303) (xy 0.1651 0.12065) (xy 0.1651 0.7366) (xy 0.16256 0.76835) (xy 0.1524 0.8001)
						(xy 0.13716 0.82804) (xy 0.11684 0.85344) (xy 0.09144 0.87376) (xy 0.0635 0.889) (xy 0.03175 0.89916)
					)
					(width 0)
					(fill yes)
				)
			)
		)
		(pad "144" smd custom
			(at 13.64996 -4.106672 180)
			(size 0.1143 0.1143)
			(layers "F.Cu" "F.Mask" "F.Paste")
			(net "M_A_DQ35")
			(options
				(clearance outline)
				(anchor circle)
			)
			(primitives
				(gr_poly
					(pts
						(xy 0 0.9017) (xy -0.03175 0.89916) (xy -0.0635 0.889) (xy -0.09144 0.87376) (xy -0.11684 0.85344)
						(xy -0.13716 0.82804) (xy -0.1524 0.8001) (xy -0.16256 0.76835) (xy -0.1651 0.7366) (xy -0.1651 0.19685)
						(xy -0.17272 0.18923) (xy -0.17907 0.18034) (xy -0.18669 0.17145) (xy -0.19177 0.16256) (xy -0.19812 0.15367)
						(xy -0.20828 0.13335) (xy -0.21971 0.10287) (xy -0.22225 0.09271) (xy -0.22479 0.08128) (xy -0.22606 0.07112)
						(xy -0.2286 0.05969) (xy -0.2286 0.01651) (xy -0.22606 0.00508) (xy -0.22479 -0.00508) (xy -0.22225 -0.01651)
						(xy -0.21971 -0.02667) (xy -0.20828 -0.05715) (xy -0.19812 -0.07747) (xy -0.19177 -0.08636) (xy -0.18669 -0.09525)
						(xy -0.17907 -0.10414) (xy -0.17272 -0.11303) (xy -0.1651 -0.12065) (xy -0.1651 -0.7366) (xy -0.16256 -0.76835)
						(xy -0.1524 -0.8001) (xy -0.13716 -0.82804) (xy -0.11684 -0.85344) (xy -0.09144 -0.87376) (xy -0.0635 -0.889)
						(xy -0.03175 -0.89916) (xy 0 -0.9017) (xy 0.03175 -0.89916) (xy 0.0635 -0.889) (xy 0.09144 -0.87376)
						(xy 0.11684 -0.85344) (xy 0.13716 -0.82804) (xy 0.1524 -0.8001) (xy 0.16256 -0.76835) (xy 0.1651 -0.7366)
						(xy 0.1651 -0.11938) (xy 0.17272 -0.11176) (xy 0.19812 -0.0762) (xy 0.2032 -0.06604) (xy 0.20701 -0.05715)
						(xy 0.21209 -0.04699) (xy 0.2159 -0.03683) (xy 0.21844 -0.02667) (xy 0.22225 -0.01524) (xy 0.22352 -0.00508)
						(xy 0.22606 0.00508) (xy 0.22733 0.01651) (xy 0.22733 0.02667) (xy 0.2286 0.0381) (xy 0.22733 0.04953)
						(xy 0.22733 0.05969) (xy 0.22606 0.07112) (xy 0.22352 0.08128) (xy 0.22225 0.09144) (xy 0.21844 0.10287)
						(xy 0.2159 0.11303) (xy 0.21209 0.12319) (xy 0.20701 0.13335) (xy 0.2032 0.14224) (xy 0.19812 0.1524)
						(xy 0.17272 0.18796) (xy 0.1651 0.19558) (xy 0.1651 0.7366) (xy 0.16256 0.76835) (xy 0.1524 0.8001)
						(xy 0.13716 0.82804) (xy 0.11684 0.85344) (xy 0.09144 0.87376) (xy 0.0635 0.889) (xy 0.03175 0.89916)
					)
					(width 0)
					(fill yes)
				)
			)
		)
		(pad "145" smd custom
			(at 13.949934 4.106672 180)
			(size 0.1143 0.1143)
			(layers "F.Cu" "F.Mask" "F.Paste")
			(net "M_A_DQ38")
			(options
				(clearance outline)
				(anchor circle)
			)
			(primitives
				(gr_poly
					(pts
						(xy 0 0.9017) (xy -0.03175 0.89916) (xy -0.0635 0.889) (xy -0.09144 0.87376) (xy -0.11684 0.85344)
						(xy -0.13716 0.82804) (xy -0.1524 0.8001) (xy -0.16256 0.76835) (xy -0.1651 0.7366) (xy -0.1651 -0.13462)
						(xy -0.17272 -0.14224) (xy -0.19812 -0.1778) (xy -0.2032 -0.18796) (xy -0.20701 -0.19685) (xy -0.21209 -0.20701)
						(xy -0.2159 -0.21717) (xy -0.21844 -0.22733) (xy -0.22225 -0.23876) (xy -0.22352 -0.24892) (xy -0.22606 -0.25908)
						(xy -0.22733 -0.27051) (xy -0.22733 -0.28067) (xy -0.2286 -0.2921) (xy -0.22733 -0.30353) (xy -0.22733 -0.31369)
						(xy -0.22606 -0.32512) (xy -0.22352 -0.33528) (xy -0.22225 -0.34544) (xy -0.21844 -0.35687) (xy -0.2159 -0.36703)
						(xy -0.21209 -0.37719) (xy -0.20701 -0.38735) (xy -0.2032 -0.39624) (xy -0.19812 -0.4064) (xy -0.17272 -0.44196)
						(xy -0.1651 -0.44958) (xy -0.1651 -0.7366) (xy -0.16256 -0.76835) (xy -0.1524 -0.8001) (xy -0.13716 -0.82804)
						(xy -0.11684 -0.85344) (xy -0.09144 -0.87376) (xy -0.0635 -0.889) (xy -0.03175 -0.89916) (xy 0 -0.9017)
						(xy 0.03175 -0.89916) (xy 0.0635 -0.889) (xy 0.09144 -0.87376) (xy 0.11684 -0.85344) (xy 0.13716 -0.82804)
						(xy 0.1524 -0.8001) (xy 0.16256 -0.76835) (xy 0.1651 -0.7366) (xy 0.1651 -0.44958) (xy 0.17272 -0.44196)
						(xy 0.19812 -0.4064) (xy 0.2032 -0.39624) (xy 0.20701 -0.38735) (xy 0.21209 -0.37719) (xy 0.2159 -0.36703)
						(xy 0.21844 -0.35687) (xy 0.22225 -0.34544) (xy 0.22352 -0.33528) (xy 0.22606 -0.32512) (xy 0.22733 -0.31369)
						(xy 0.22733 -0.30353) (xy 0.2286 -0.2921) (xy 0.22733 -0.28067) (xy 0.22733 -0.27051) (xy 0.22606 -0.25908)
						(xy 0.22352 -0.24892) (xy 0.22225 -0.23876) (xy 0.21844 -0.22733) (xy 0.2159 -0.21717) (xy 0.21209 -0.20701)
						(xy 0.20701 -0.19685) (xy 0.2032 -0.18796) (xy 0.19812 -0.1778) (xy 0.17272 -0.14224) (xy 0.1651 -0.13462)
						(xy 0.1651 0.7366) (xy 0.16256 0.76835) (xy 0.1524 0.8001) (xy 0.13716 0.82804) (xy 0.11684 0.85344)
						(xy 0.09144 0.87376) (xy 0.0635 0.889) (xy 0.03175 0.89916)
					)
					(width 0)
					(fill yes)
				)
			)
		)
		(pad "146" smd custom
			(at 14.249908 -4.106672 180)
			(size 0.1143 0.1143)
			(layers "F.Cu" "F.Mask" "F.Paste")
			(net "GND")
			(options
				(clearance outline)
				(anchor circle)
			)
			(primitives
				(gr_poly
					(pts
						(xy 0 0.9017) (xy -0.03175 0.89916) (xy -0.0635 0.889) (xy -0.09144 0.87376) (xy -0.11684 0.85344)
						(xy -0.13716 0.82804) (xy -0.1524 0.8001) (xy -0.16256 0.76835) (xy -0.1651 0.7366) (xy -0.1651 0.44958)
						(xy -0.17272 0.44196) (xy -0.19812 0.4064) (xy -0.2032 0.39624) (xy -0.20701 0.38735) (xy -0.21209 0.37719)
						(xy -0.2159 0.36703) (xy -0.21844 0.35687) (xy -0.22225 0.34544) (xy -0.22352 0.33528) (xy -0.22606 0.32512)
						(xy -0.22733 0.31369) (xy -0.22733 0.30353) (xy -0.2286 0.2921) (xy -0.22733 0.28067) (xy -0.22733 0.27051)
						(xy -0.22606 0.25908) (xy -0.22352 0.24892) (xy -0.22225 0.23876) (xy -0.21844 0.22733) (xy -0.2159 0.21717)
						(xy -0.21209 0.20701) (xy -0.20701 0.19685) (xy -0.2032 0.18796) (xy -0.19812 0.1778) (xy -0.17272 0.14224)
						(xy -0.1651 0.13462) (xy -0.1651 -0.7366) (xy -0.16256 -0.76835) (xy -0.1524 -0.8001) (xy -0.13716 -0.82804)
						(xy -0.11684 -0.85344) (xy -0.09144 -0.87376) (xy -0.0635 -0.889) (xy -0.03175 -0.89916) (xy 0 -0.9017)
						(xy 0.03175 -0.89916) (xy 0.0635 -0.889) (xy 0.09144 -0.87376) (xy 0.11684 -0.85344) (xy 0.13716 -0.82804)
						(xy 0.1524 -0.8001) (xy 0.16256 -0.76835) (xy 0.1651 -0.7366) (xy 0.1651 0.13462) (xy 0.17272 0.14224)
						(xy 0.19812 0.1778) (xy 0.2032 0.18796) (xy 0.20701 0.19685) (xy 0.21209 0.20701) (xy 0.2159 0.21717)
						(xy 0.21844 0.22733) (xy 0.22225 0.23876) (xy 0.22352 0.24892) (xy 0.22606 0.25908) (xy 0.22733 0.27051)
						(xy 0.22733 0.28067) (xy 0.2286 0.2921) (xy 0.22733 0.30353) (xy 0.22733 0.31369) (xy 0.22606 0.32512)
						(xy 0.22352 0.33528) (xy 0.22225 0.34544) (xy 0.21844 0.35687) (xy 0.2159 0.36703) (xy 0.21209 0.37719)
						(xy 0.20701 0.38735) (xy 0.2032 0.39624) (xy 0.19812 0.4064) (xy 0.17272 0.44196) (xy 0.1651 0.44958)
						(xy 0.1651 0.7366) (xy 0.16256 0.76835) (xy 0.1524 0.8001) (xy 0.13716 0.82804) (xy 0.11684 0.85344)
						(xy 0.09144 0.87376) (xy 0.0635 0.889) (xy 0.03175 0.89916)
					)
					(width 0)
					(fill yes)
				)
			)
		)
	)
)
